(kicad_pcb
	(version 20260206)
	(generator "pcbnew")
	(generator_version "10.0")
	(general
		(thickness 1.6)
		(legacy_teardrops no)
	)
	(paper "A4")
	(title_block
		(title "v1-chassis-manager — T6M_CM_d_v01_1031_1645.brd")
		(comment 1 "Open CloudServer (Microsoft) / footprint 1308 of 2512 (U125), pads 1-117 of 128")
	)
	(layers
		(0 "F.Cu" signal "TOP")
		(4 "In1.Cu" signal "GND1")
		(6 "In2.Cu" signal "IN1")
		(8 "In3.Cu" signal "VCC1")
		(10 "In4.Cu" signal "VCC2")
		(12 "In5.Cu" signal "GND2")
		(14 "In6.Cu" signal "IN2")
		(16 "In7.Cu" signal "IN3")
		(18 "In8.Cu" signal "GND3")
		(2 "B.Cu" signal "BOTTOM")
		(9 "F.Adhes" user "F.Adhesive")
		(11 "B.Adhes" user "B.Adhesive")
		(13 "F.Paste" user "Package Geometry/Pastemask Top")
		(15 "B.Paste" user "Package Geometry/Pastemask Bottom")
		(5 "F.SilkS" user "Ref Des/Silkscreen Top")
		(7 "B.SilkS" user "Ref Des/Silkscreen Bottom")
		(1 "F.Mask" user "Board Geometry/Soldermask Top")
		(3 "B.Mask" user "Board Geometry/Soldermask Bottom")
		(17 "Dwgs.User" user "User.Drawings")
		(19 "Cmts.User" user "User.Comments")
		(21 "Eco1.User" user "User.Eco1")
		(23 "Eco2.User" user "User.Eco2")
		(25 "Edge.Cuts" user "Board Geometry/Outline")
		(27 "Margin" user)
		(31 "F.CrtYd" user "Package Geometry/Place Bound Top")
		(29 "B.CrtYd" user "Package Geometry/Place Bound Bottom")
		(35 "F.Fab" user "Ref Des/Assembly Top")
		(33 "B.Fab" user "Ref Des/Assembly Bottom")
	)
	(footprint ""
		(layer "F.Cu")
		(at 133.53796 -143.575532 90)
		(property "Reference" "U125"
			(at -10.804652 0.525272 0)
			(unlocked yes)
			(layer "F.SilkS")
			(effects
				(font
					(size 0.7874 0.5842)
					(thickness 0.1524)
				)
				(justify left)
			)
		)
		(property "Value" ""
			(at 0 0 90)
			(layer "F.Fab")
			(effects
				(font
					(size 1.27 1.27)
				)
			)
		)
		(duplicate_pad_numbers_are_jumpers no)
		(pad "1" smd rect
			(at -6.199886 7.750048 90)
			(size 0.1778 1.524)
			(layers "F.Cu" "F.Mask" "F.Paste")
			(net "P1V0_NODE1")
		)
		(pad "2" smd rect
			(at -5.80009 7.750048 90)
			(size 0.1778 1.524)
			(layers "F.Cu" "F.Mask" "F.Paste")
			(net "GND")
		)
		(pad "3" smd rect
			(at -5.40004 7.750048 90)
			(size 0.1778 1.524)
			(layers "F.Cu" "F.Mask" "F.Paste")
			(net "GND")
		)
		(pad "4" smd rect
			(at -4.99999 7.750048 90)
			(size 0.1778 1.524)
			(layers "F.Cu" "F.Mask" "F.Paste")
			(net "P1V0_NODE1")
		)
		(pad "5" smd rect
			(at -4.59994 7.750048 90)
			(size 0.1778 1.524)
			(layers "F.Cu" "F.Mask" "F.Paste")
			(net "P3V3_NODE1")
		)
		(pad "6" smd rect
			(at -4.19989 7.750048 90)
			(size 0.1778 1.524)
			(layers "F.Cu" "F.Mask" "F.Paste")
			(net "PCIE_SW_WAKE_N")
		)
		(pad "7" smd rect
			(at -3.800094 7.750048 90)
			(size 0.1778 1.524)
			(layers "F.Cu" "F.Mask" "F.Paste")
			(net "PCIE_SW_PRSNT2")
		)
		(pad "8" smd rect
			(at -3.400044 7.750048 90)
			(size 0.1778 1.524)
			(layers "F.Cu" "F.Mask" "F.Paste")
			(net "P3V3_NODE1")
		)
		(pad "9" smd rect
			(at -2.999994 7.750048 90)
			(size 0.1778 1.524)
			(layers "F.Cu" "F.Mask" "F.Paste")
			(net "Net_2284")
		)
		(pad "10" smd rect
			(at -2.599944 7.750048 90)
			(size 0.1778 1.524)
			(layers "F.Cu" "F.Mask" "F.Paste")
			(net "PCIE_SW_TEST5")
		)
		(pad "11" smd rect
			(at -2.199894 7.750048 90)
			(size 0.1778 1.524)
			(layers "F.Cu" "F.Mask" "F.Paste")
			(net "PCIE_SW_TEST4")
		)
		(pad "12" smd rect
			(at -1.800098 7.750048 90)
			(size 0.1778 1.524)
			(layers "F.Cu" "F.Mask" "F.Paste")
			(net "PCIE_SW_TEST3")
		)
		(pad "13" smd rect
			(at -1.400048 7.750048 90)
			(size 0.1778 1.524)
			(layers "F.Cu" "F.Mask" "F.Paste")
			(net "PCIE_SW_I2C_SCL")
		)
		(pad "14" smd rect
			(at -0.999998 7.750048 90)
			(size 0.1778 1.524)
			(layers "F.Cu" "F.Mask" "F.Paste")
			(net "GND")
		)
		(pad "15" smd rect
			(at -0.599948 7.750048 90)
			(size 0.1778 1.524)
			(layers "F.Cu" "F.Mask" "F.Paste")
			(net "P1V0_NODE1")
		)
		(pad "16" smd rect
			(at -0.199898 7.750048 90)
			(size 0.1778 1.524)
			(layers "F.Cu" "F.Mask" "F.Paste")
			(net "PCIE_SW_I2C_SDA")
		)
		(pad "17" smd rect
			(at 0.199898 7.750048 90)
			(size 0.1778 1.524)
			(layers "F.Cu" "F.Mask" "F.Paste")
			(net "PCIE_SW_PWR_SAV")
		)
		(pad "18" smd rect
			(at 0.599948 7.750048 90)
			(size 0.1778 1.524)
			(layers "F.Cu" "F.Mask" "F.Paste")
			(net "PCIE_SW_P0_CTCDIS")
		)
		(pad "19" smd rect
			(at 0.999998 7.750048 90)
			(size 0.1778 1.524)
			(layers "F.Cu" "F.Mask" "F.Paste")
			(net "GND")
		)
		(pad "20" smd rect
			(at 1.400048 7.750048 90)
			(size 0.1778 1.524)
			(layers "F.Cu" "F.Mask" "F.Paste")
			(net "P3V3_NODE1")
		)
		(pad "21" smd rect
			(at 1.800098 7.750048 90)
			(size 0.1778 1.524)
			(layers "F.Cu" "F.Mask" "F.Paste")
			(net "Net_2292")
		)
		(pad "22" smd rect
			(at 2.199894 7.750048 90)
			(size 0.1778 1.524)
			(layers "F.Cu" "F.Mask" "F.Paste")
			(net "Net_2291")
		)
		(pad "23" smd rect
			(at 2.599944 7.750048 90)
			(size 0.1778 1.524)
			(layers "F.Cu" "F.Mask" "F.Paste")
			(net "Net_2290")
		)
		(pad "24" smd rect
			(at 2.999994 7.750048 90)
			(size 0.1778 1.524)
			(layers "F.Cu" "F.Mask" "F.Paste")
			(net "Net_2289")
		)
		(pad "25" smd rect
			(at 3.400044 7.750048 90)
			(size 0.1778 1.524)
			(layers "F.Cu" "F.Mask" "F.Paste")
			(net "Net_2288")
		)
		(pad "26" smd rect
			(at 3.800094 7.750048 90)
			(size 0.1778 1.524)
			(layers "F.Cu" "F.Mask" "F.Paste")
			(net "PCIE_SW_GPIO5")
		)
		(pad "27" smd rect
			(at 4.19989 7.750048 90)
			(size 0.1778 1.524)
			(layers "F.Cu" "F.Mask" "F.Paste")
			(net "PCIE_SW_GPIO6")
		)
		(pad "28" smd rect
			(at 4.59994 7.750048 90)
			(size 0.1778 1.524)
			(layers "F.Cu" "F.Mask" "F.Paste")
			(net "PCIE_SW_GPIO7")
		)
		(pad "29" smd rect
			(at 4.99999 7.750048 90)
			(size 0.1778 1.524)
			(layers "F.Cu" "F.Mask" "F.Paste")
			(net "P1V0_NODE1")
		)
		(pad "30" smd rect
			(at 5.40004 7.750048 90)
			(size 0.1778 1.524)
			(layers "F.Cu" "F.Mask" "F.Paste")
			(net "GND")
		)
		(pad "31" smd rect
			(at 5.80009 7.750048 90)
			(size 0.1778 1.524)
			(layers "F.Cu" "F.Mask" "F.Paste")
			(net "PCIE_SW_TEST1")
		)
		(pad "32" smd rect
			(at 6.199886 7.750048 90)
			(size 0.1778 1.524)
			(layers "F.Cu" "F.Mask" "F.Paste")
			(net "PCIE_SW_P1_CTCDIS")
		)
		(pad "33" smd rect
			(at 7.750048 6.199886 180)
			(size 0.1778 1.524)
			(layers "F.Cu" "F.Mask" "F.Paste")
			(net "PCIE_SW_P2_CTCDIS")
		)
		(pad "34" smd rect
			(at 7.750048 5.80009 180)
			(size 0.1778 1.524)
			(layers "F.Cu" "F.Mask" "F.Paste")
			(net "GND")
		)
		(pad "35" smd rect
			(at 7.750048 5.40004 180)
			(size 0.1778 1.524)
			(layers "F.Cu" "F.Mask" "F.Paste")
			(net "P3V3_NODE1")
		)
		(pad "36" smd rect
			(at 7.750048 4.99999 180)
			(size 0.1778 1.524)
			(layers "F.Cu" "F.Mask" "F.Paste")
			(net "GND")
		)
		(pad "37" smd rect
			(at 7.750048 4.59994 180)
			(size 0.1778 1.524)
			(layers "F.Cu" "F.Mask" "F.Paste")
			(net "P1V0_NODE1")
		)
		(pad "38" smd rect
			(at 7.750048 4.19989 180)
			(size 0.1778 1.524)
			(layers "F.Cu" "F.Mask" "F.Paste")
			(net "PCIE_SW_TEST7")
		)
		(pad "39" smd rect
			(at 7.750048 3.800094 180)
			(size 0.1778 1.524)
			(layers "F.Cu" "F.Mask" "F.Paste")
			(net "P3V3_NODE1")
		)
		(pad "40" smd rect
			(at 7.750048 3.400044 180)
			(size 0.1778 1.524)
			(layers "F.Cu" "F.Mask" "F.Paste")
			(net "PCIE_SW_EEPROM_CLK")
		)
		(pad "41" smd rect
			(at 7.750048 2.999994 180)
			(size 0.1778 1.524)
			(layers "F.Cu" "F.Mask" "F.Paste")
			(net "PCIE_SW_EEPROM_DAT")
		)
		(pad "42" smd rect
			(at 7.750048 2.599944 180)
			(size 0.1778 1.524)
			(layers "F.Cu" "F.Mask" "F.Paste")
			(net "P1V0_NODE1")
		)
		(pad "43" smd rect
			(at 7.750048 2.199894 180)
			(size 0.1778 1.524)
			(layers "F.Cu" "F.Mask" "F.Paste")
			(net "PCIE_SW_RST_N")
		)
		(pad "44" smd rect
			(at 7.750048 1.800098 180)
			(size 0.1778 1.524)
			(layers "F.Cu" "F.Mask" "F.Paste")
			(net "GND")
		)
		(pad "45" smd rect
			(at 7.750048 1.400048 180)
			(size 0.1778 1.524)
			(layers "F.Cu" "F.Mask" "F.Paste")
			(net "PCIE_SW_P0_ERR_R")
		)
		(pad "46" smd rect
			(at 7.750048 0.999998 180)
			(size 0.1778 1.524)
			(layers "F.Cu" "F.Mask" "F.Paste")
			(net "P1V0_NODE1")
		)
		(pad "47" smd rect
			(at 7.750048 0.599948 180)
			(size 0.1778 1.524)
			(layers "F.Cu" "F.Mask" "F.Paste")
			(net "Net_2282")
		)
		(pad "48" smd rect
			(at 7.750048 0.199898 180)
			(size 0.1778 1.524)
			(layers "F.Cu" "F.Mask" "F.Paste")
			(net "P3V3_NODE1")
		)
		(pad "49" smd rect
			(at 7.750048 -0.199898 180)
			(size 0.1778 1.524)
			(layers "F.Cu" "F.Mask" "F.Paste")
			(net "P1V0_NODE1")
		)
		(pad "50" smd rect
			(at 7.750048 -0.599948 180)
			(size 0.1778 1.524)
			(layers "F.Cu" "F.Mask" "F.Paste")
			(net "GND")
		)
		(pad "51" smd rect
			(at 7.750048 -0.999998 180)
			(size 0.1778 1.524)
			(layers "F.Cu" "F.Mask" "F.Paste")
			(net "Net_2281")
		)
		(pad "52" smd rect
			(at 7.750048 -1.400048 180)
			(size 0.1778 1.524)
			(layers "F.Cu" "F.Mask" "F.Paste")
			(net "P1V0_NODE1")
		)
		(pad "53" smd rect
			(at 7.750048 -1.800098 180)
			(size 0.1778 1.524)
			(layers "F.Cu" "F.Mask" "F.Paste")
			(net "GND")
		)
		(pad "54" smd rect
			(at 7.750048 -2.199894 180)
			(size 0.1778 1.524)
			(layers "F.Cu" "F.Mask" "F.Paste")
			(net "Net_2283")
		)
		(pad "55" smd rect
			(at 7.750048 -2.599944 180)
			(size 0.1778 1.524)
			(layers "F.Cu" "F.Mask" "F.Paste")
			(net "P3V3_NODE1")
		)
		(pad "56" smd rect
			(at 7.750048 -2.999994 180)
			(size 0.1778 1.524)
			(layers "F.Cu" "F.Mask" "F.Paste")
			(net "PCIE_SW_SCAN_EN")
		)
		(pad "57" smd rect
			(at 7.750048 -3.400044 180)
			(size 0.1778 1.524)
			(layers "F.Cu" "F.Mask" "F.Paste")
			(net "GND")
		)
		(pad "58" smd rect
			(at 7.750048 -3.800094 180)
			(size 0.1778 1.524)
			(layers "F.Cu" "F.Mask" "F.Paste")
			(net "Net_2285")
		)
		(pad "59" smd rect
			(at 7.750048 -4.19989 180)
			(size 0.1778 1.524)
			(layers "F.Cu" "F.Mask" "F.Paste")
			(net "Net_2287")
		)
		(pad "60" smd rect
			(at 7.750048 -4.59994 180)
			(size 0.1778 1.524)
			(layers "F.Cu" "F.Mask" "F.Paste")
			(net "GND")
		)
		(pad "61" smd rect
			(at 7.750048 -4.99999 180)
			(size 0.1778 1.524)
			(layers "F.Cu" "F.Mask" "F.Paste")
			(net "P1V0_NODE1")
		)
		(pad "62" smd rect
			(at 7.750048 -5.40004 180)
			(size 0.1778 1.524)
			(layers "F.Cu" "F.Mask" "F.Paste")
			(net "GND")
		)
		(pad "63" smd rect
			(at 7.750048 -5.80009 180)
			(size 0.1778 1.524)
			(layers "F.Cu" "F.Mask" "F.Paste")
			(net "PCIE_SW_TMS")
		)
		(pad "64" smd rect
			(at 7.750048 -6.199886 180)
			(size 0.1778 1.524)
			(layers "F.Cu" "F.Mask" "F.Paste")
			(net "Net_2286")
		)
		(pad "65" smd rect
			(at 6.199886 -7.750048 90)
			(size 0.1778 1.524)
			(layers "F.Cu" "F.Mask" "F.Paste")
			(net "PCIE_SW_TRST")
		)
		(pad "66" smd rect
			(at 5.80009 -7.750048 90)
			(size 0.1778 1.524)
			(layers "F.Cu" "F.Mask" "F.Paste")
			(net "PCIE_SW_TEST2")
		)
		(pad "67" smd rect
			(at 5.40004 -7.750048 90)
			(size 0.1778 1.524)
			(layers "F.Cu" "F.Mask" "F.Paste")
			(net "GND")
		)
		(pad "68" smd rect
			(at 4.99999 -7.750048 90)
			(size 0.1778 1.524)
			(layers "F.Cu" "F.Mask" "F.Paste")
			(net "GND")
		)
		(pad "69" smd rect
			(at 4.59994 -7.750048 90)
			(size 0.1778 1.524)
			(layers "F.Cu" "F.Mask" "F.Paste")
			(net "P2E_CPU_PCIE_SW_NODE1_TX_DN")
		)
		(pad "70" smd rect
			(at 4.19989 -7.750048 90)
			(size 0.1778 1.524)
			(layers "F.Cu" "F.Mask" "F.Paste")
			(net "P2E_CPU_PCIE_SW_NODE1_TX_DP")
		)
		(pad "71" smd rect
			(at 3.800094 -7.750048 90)
			(size 0.1778 1.524)
			(layers "F.Cu" "F.Mask" "F.Paste")
			(net "GND")
		)
		(pad "72" smd rect
			(at 3.400044 -7.750048 90)
			(size 0.1778 1.524)
			(layers "F.Cu" "F.Mask" "F.Paste")
			(net "P1V0_NODE1")
		)
		(pad "73" smd rect
			(at 2.999994 -7.750048 90)
			(size 0.1778 1.524)
			(layers "F.Cu" "F.Mask" "F.Paste")
			(net "P2E_CPU_PCIE_SW_NODE1_RX_C_DP")
		)
		(pad "74" smd rect
			(at 2.599944 -7.750048 90)
			(size 0.1778 1.524)
			(layers "F.Cu" "F.Mask" "F.Paste")
			(net "P2E_CPU_PCIE_SW_NODE1_RX_C_DN")
		)
		(pad "75" smd rect
			(at 2.199894 -7.750048 90)
			(size 0.1778 1.524)
			(layers "F.Cu" "F.Mask" "F.Paste")
			(net "P1V538_BMC_NODE1")
		)
		(pad "76" smd rect
			(at 1.800098 -7.750048 90)
			(size 0.1778 1.524)
			(layers "F.Cu" "F.Mask" "F.Paste")
			(net "P1V0_NODE1")
		)
		(pad "77" smd rect
			(at 1.400048 -7.750048 90)
			(size 0.1778 1.524)
			(layers "F.Cu" "F.Mask" "F.Paste")
			(net "GND")
		)
		(pad "78" smd rect
			(at 0.999998 -7.750048 90)
			(size 0.1778 1.524)
			(layers "F.Cu" "F.Mask" "F.Paste")
			(net "P1V0_PCI_SW_A")
		)
		(pad "79" smd rect
			(at 0.599948 -7.750048 90)
			(size 0.1778 1.524)
			(layers "F.Cu" "F.Mask" "F.Paste")
			(net "P1V0_PCI_SW_A")
		)
		(pad "80" smd rect
			(at 0.199898 -7.750048 90)
			(size 0.1778 1.524)
			(layers "F.Cu" "F.Mask" "F.Paste")
			(net "P1V0_PCI_SW_A")
		)
		(pad "81" smd rect
			(at -0.199898 -7.750048 90)
			(size 0.1778 1.524)
			(layers "F.Cu" "F.Mask" "F.Paste")
			(net "GND")
		)
		(pad "82" smd rect
			(at -0.599948 -7.750048 90)
			(size 0.1778 1.524)
			(layers "F.Cu" "F.Mask" "F.Paste")
			(net "P1V538_BMC_NODE1")
		)
		(pad "83" smd rect
			(at -0.999998 -7.750048 90)
			(size 0.1778 1.524)
			(layers "F.Cu" "F.Mask" "F.Paste")
			(net "P2E_CPU_BMC_NODE1_TX_C_DN")
		)
		(pad "84" smd rect
			(at -1.400048 -7.750048 90)
			(size 0.1778 1.524)
			(layers "F.Cu" "F.Mask" "F.Paste")
			(net "P2E_CPU_BMC_NODE1_TX_C_DP")
		)
		(pad "85" smd rect
			(at -1.800098 -7.750048 90)
			(size 0.1778 1.524)
			(layers "F.Cu" "F.Mask" "F.Paste")
			(net "P1V0_NODE1")
		)
		(pad "86" smd rect
			(at -2.199894 -7.750048 90)
			(size 0.1778 1.524)
			(layers "F.Cu" "F.Mask" "F.Paste")
			(net "GND")
		)
		(pad "87" smd rect
			(at -2.599944 -7.750048 90)
			(size 0.1778 1.524)
			(layers "F.Cu" "F.Mask" "F.Paste")
			(net "P2E_CPU_BMC_NODE1_RX_DP")
		)
		(pad "88" smd rect
			(at -2.999994 -7.750048 90)
			(size 0.1778 1.524)
			(layers "F.Cu" "F.Mask" "F.Paste")
			(net "P2E_CPU_BMC_NODE1_RX_DN")
		)
		(pad "89" smd rect
			(at -3.400044 -7.750048 90)
			(size 0.1778 1.524)
			(layers "F.Cu" "F.Mask" "F.Paste")
			(net "GND")
		)
		(pad "90" smd rect
			(at -3.800094 -7.750048 90)
			(size 0.1778 1.524)
			(layers "F.Cu" "F.Mask" "F.Paste")
			(net "GND")
		)
		(pad "91" smd rect
			(at -4.19989 -7.750048 90)
			(size 0.1778 1.524)
			(layers "F.Cu" "F.Mask" "F.Paste")
			(net "CLK_100M_PCIE_SW_NODE1_C_DP")
		)
		(pad "92" smd rect
			(at -4.59994 -7.750048 90)
			(size 0.1778 1.524)
			(layers "F.Cu" "F.Mask" "F.Paste")
			(net "P1V0_PCI_SW_A")
		)
		(pad "93" smd rect
			(at -4.99999 -7.750048 90)
			(size 0.1778 1.524)
			(layers "F.Cu" "F.Mask" "F.Paste")
			(net "CLK_100M_PCIE_SW_NODE1_C_DN")
		)
		(pad "94" smd rect
			(at -5.40004 -7.750048 90)
			(size 0.1778 1.524)
			(layers "F.Cu" "F.Mask" "F.Paste")
			(net "GND")
		)
		(pad "95" smd rect
			(at -5.80009 -7.750048 90)
			(size 0.1778 1.524)
			(layers "F.Cu" "F.Mask" "F.Paste")
			(net "GND")
		)
		(pad "96" smd rect
			(at -6.199886 -7.750048 90)
			(size 0.1778 1.524)
			(layers "F.Cu" "F.Mask" "F.Paste")
			(net "PE_SW_BMC_PERST_L")
		)
		(pad "97" smd rect
			(at -7.750048 -6.199886 180)
			(size 0.1778 1.524)
			(layers "F.Cu" "F.Mask" "F.Paste")
			(net "PE_SW_USB_PERST_L")
		)
		(pad "98" smd rect
			(at -7.750048 -5.80009 180)
			(size 0.1778 1.524)
			(layers "F.Cu" "F.Mask" "F.Paste")
			(net "Net_2280")
		)
		(pad "99" smd rect
			(at -7.750048 -5.40004 180)
			(size 0.1778 1.524)
			(layers "F.Cu" "F.Mask" "F.Paste")
			(net "P3V3_NODE1")
		)
		(pad "100" smd rect
			(at -7.750048 -4.99999 180)
			(size 0.1778 1.524)
			(layers "F.Cu" "F.Mask" "F.Paste")
			(net "GND")
		)
		(pad "101" smd rect
			(at -7.750048 -4.59994 180)
			(size 0.1778 1.524)
			(layers "F.Cu" "F.Mask" "F.Paste")
			(net "P1V0_NODE1")
		)
		(pad "102" smd rect
			(at -7.750048 -4.19989 180)
			(size 0.1778 1.524)
			(layers "F.Cu" "F.Mask" "F.Paste")
			(net "GND")
		)
		(pad "103" smd rect
			(at -7.750048 -3.800094 180)
			(size 0.1778 1.524)
			(layers "F.Cu" "F.Mask" "F.Paste")
			(net "P2E_CPU_USB_NODE1_RX_DN")
		)
		(pad "104" smd rect
			(at -7.750048 -3.400044 180)
			(size 0.1778 1.524)
			(layers "F.Cu" "F.Mask" "F.Paste")
			(net "P2E_CPU_USB_NODE1_RX_DP")
		)
		(pad "105" smd rect
			(at -7.750048 -2.999994 180)
			(size 0.1778 1.524)
			(layers "F.Cu" "F.Mask" "F.Paste")
			(net "GND")
		)
		(pad "106" smd rect
			(at -7.750048 -2.599944 180)
			(size 0.1778 1.524)
			(layers "F.Cu" "F.Mask" "F.Paste")
			(net "P1V0_NODE1")
		)
		(pad "107" smd rect
			(at -7.750048 -2.199894 180)
			(size 0.1778 1.524)
			(layers "F.Cu" "F.Mask" "F.Paste")
			(net "P2E_CPU_USB_NODE1_TX_C_DP")
		)
		(pad "108" smd rect
			(at -7.750048 -1.800098 180)
			(size 0.1778 1.524)
			(layers "F.Cu" "F.Mask" "F.Paste")
			(net "P2E_CPU_USB_NODE1_TX_C_DN")
		)
		(pad "109" smd rect
			(at -7.750048 -1.400048 180)
			(size 0.1778 1.524)
			(layers "F.Cu" "F.Mask" "F.Paste")
			(net "P1V538_BMC_NODE1")
		)
		(pad "110" smd rect
			(at -7.750048 -0.999998 180)
			(size 0.1778 1.524)
			(layers "F.Cu" "F.Mask" "F.Paste")
			(net "P1V0_NODE1")
		)
		(pad "111" smd rect
			(at -7.750048 -0.599948 180)
			(size 0.1778 1.524)
			(layers "F.Cu" "F.Mask" "F.Paste")
			(net "GND")
		)
		(pad "112" smd rect
			(at -7.750048 -0.199898 180)
			(size 0.1778 1.524)
			(layers "F.Cu" "F.Mask" "F.Paste")
			(net "P1V0_PCI_SW_A")
		)
		(pad "113" smd rect
			(at -7.750048 0.199898 180)
			(size 0.1778 1.524)
			(layers "F.Cu" "F.Mask" "F.Paste")
			(net "P1V0_PCI_SW_A")
		)
		(pad "114" smd rect
			(at -7.750048 0.599948 180)
			(size 0.1778 1.524)
			(layers "F.Cu" "F.Mask" "F.Paste")
			(net "GND")
		)
		(pad "115" smd rect
			(at -7.750048 0.999998 180)
			(size 0.1778 1.524)
			(layers "F.Cu" "F.Mask" "F.Paste")
			(net "P1V538_BMC_NODE1")
		)
		(pad "116" smd rect
			(at -7.750048 1.400048 180)
			(size 0.1778 1.524)
			(layers "F.Cu" "F.Mask" "F.Paste")
			(net "Net_2279")
		)
		(pad "117" smd rect
			(at -7.750048 1.800098 180)
			(size 0.1778 1.524)
			(layers "F.Cu" "F.Mask" "F.Paste")
			(net "Net_2278")
		)
	)
)
